(kicad_pcb
	(version 20241229)
	(generator "pcbnew")
	(generator_version "9.0")
	(general
		(thickness 1.711)
		(legacy_teardrops no)
	)
	(paper "A4")
	(title_block
		(title "Antmicro Baseboard for Jetson AGX Thor")
		(date "2026-02-18")
		(rev "1.1.0")
		(company "Antmicro Ltd")
		(comment 1 "www.antmicro.com")
		(comment 9 "footprints 700-704 of 1170")
	)
	(layers
		(0 "F.Cu" signal)
		(4 "In1.Cu" signal)
		(6 "In2.Cu" signal)
		(8 "In3.Cu" signal)
		(10 "In4.Cu" jumper)
		(12 "In5.Cu" signal)
		(14 "In6.Cu" signal)
		(16 "In7.Cu" signal)
		(18 "In8.Cu" signal)
		(2 "B.Cu" signal)
		(9 "F.Adhes" user "F.Adhesive")
		(11 "B.Adhes" user "B.Adhesive")
		(13 "F.Paste" user)
		(15 "B.Paste" user)
		(5 "F.SilkS" user "F.Silkscreen")
		(7 "B.SilkS" user "B.Silkscreen")
		(1 "F.Mask" user)
		(3 "B.Mask" user)
		(17 "Dwgs.User" user "User.Drawings")
		(19 "Cmts.User" user "User.Comments")
		(21 "Eco1.User" user "User.Eco1")
		(23 "Eco2.User" user "User.Eco2")
		(25 "Edge.Cuts" user)
		(27 "Margin" user)
		(31 "F.CrtYd" user "F.Courtyard")
		(29 "B.CrtYd" user "B.Courtyard")
		(35 "F.Fab" user)
		(33 "B.Fab" user)
	)
	(footprint "antmicro-footprints:SOT-523"
		(layer "B.Cu")
		(at 99.15 65.51 -90)
		(property "Reference" "Q37"
			(at -0.91 1.25 90)
			(layer "B.SilkS")
			(effects
				(font
					(size 0.7 0.7)
					(thickness 0.15)
				)
				(justify left bottom mirror)
			)
		)
		(property "Value" "DMG1012T-7"
			(at 0.1 -1.824 90)
			(layer "B.Fab")
			(effects
				(font
					(size 0.7 0.7)
					(thickness 0.15)
				)
				(justify left bottom mirror)
			)
		)
		(property "Datasheet" "https://www.diodes.com/assets/Datasheets/ds31783.pdf"
			(at 0 0 90)
			(layer "B.Fab")
			(hide yes)
			(effects
				(font
					(size 1.27 1.27)
					(thickness 0.15)
				)
				(justify mirror)
			)
		)
		(property "Description" "Power MOSFET, N Channel, 20 V, 630 mA, 0.3 ohm, SOT-523, Surface Mount"
			(at 0 0 90)
			(layer "B.Fab")
			(hide yes)
			(effects
				(font
					(size 1.27 1.27)
					(thickness 0.15)
				)
				(justify mirror)
			)
		)
		(property "MPN" "DMG1012T-7"
			(at 0 0 90)
			(unlocked yes)
			(layer "B.Fab")
			(hide yes)
			(effects
				(font
					(size 1 1)
					(thickness 0.15)
				)
				(justify mirror)
			)
		)
		(property "Manufacturer" "Diodes Incorporated"
			(at 0 0 90)
			(unlocked yes)
			(layer "B.Fab")
			(hide yes)
			(effects
				(font
					(size 1 1)
					(thickness 0.15)
				)
				(justify mirror)
			)
		)
		(property "Author" "Antmicro"
			(at 0 0 90)
			(unlocked yes)
			(layer "B.Fab")
			(hide yes)
			(effects
				(font
					(size 1 1)
					(thickness 0.15)
				)
				(justify mirror)
			)
		)
		(property "License" "Apache-2.0"
			(at 0 0 90)
			(unlocked yes)
			(layer "B.Fab")
			(hide yes)
			(effects
				(font
					(size 1 1)
					(thickness 0.15)
				)
				(justify mirror)
			)
		)
		(sheetname "/SoM_Power/")
		(sheetfile "som_power.kicad_sch")
		(attr smd)
		(fp_line
			(start -0.725 0.551)
			(end -0.277 0.551)
			(stroke
				(width 0.15)
				(type solid)
			)
			(layer "B.SilkS")
		)
		(fp_line
			(start -0.277 0.551)
			(end -0.277 0.75)
			(stroke
				(width 0.15)
				(type solid)
			)
			(layer "B.SilkS")
		)
		(fp_line
			(start -0.927 0.351)
			(end -0.725 0.551)
			(stroke
				(width 0.15)
				(type solid)
			)
			(layer "B.SilkS")
		)
		(fp_line
			(start -0.927 0.051)
			(end -0.927 0.351)
			(stroke
				(width 0.15)
				(type solid)
			)
			(layer "B.SilkS")
		)
		(fp_circle
			(center -0.9652 -0.9652)
			(end -0.9152 -0.9652)
			(stroke
				(width 0.15)
				(type solid)
			)
			(fill yes)
			(layer "B.SilkS")
		)
		(fp_line
			(start -1.12 1.16)
			(end 1.1 1.16)
			(stroke
				(width 0.05)
				(type solid)
			)
			(layer "B.CrtYd")
		)
		(fp_line
			(start -1.12 1.16)
			(end -1.12 -1.15)
			(stroke
				(width 0.05)
				(type solid)
			)
			(layer "B.CrtYd")
		)
		(fp_line
			(start 1.1 1.16)
			(end 1.1 -1.15)
			(stroke
				(width 0.05)
				(type solid)
			)
			(layer "B.CrtYd")
		)
		(fp_line
			(start -1.12 -1.15)
			(end 1.1 -1.15)
			(stroke
				(width 0.05)
				(type solid)
			)
			(layer "B.CrtYd")
		)
		(fp_line
			(start -0.652 0.425)
			(end -0.802 0.276)
			(stroke
				(width 0.15)
				(type solid)
			)
			(layer "B.Fab")
		)
		(fp_line
			(start 0.8 0.425)
			(end -0.652 0.425)
			(stroke
				(width 0.15)
				(type solid)
			)
			(layer "B.Fab")
		)
		(fp_line
			(start 0.8 0.425)
			(end 0.8 -0.424)
			(stroke
				(width 0.15)
				(type solid)
			)
			(layer "B.Fab")
		)
		(fp_line
			(start -0.802 0.276)
			(end -0.802 -0.424)
			(stroke
				(width 0.15)
				(type solid)
			)
			(layer "B.Fab")
		)
		(fp_line
			(start 0.8 -0.424)
			(end -0.802 -0.424)
			(stroke
				(width 0.15)
				(type solid)
			)
			(layer "B.Fab")
		)
		(fp_circle
			(center -0.9652 -0.9652)
			(end -0.9144 -0.9652)
			(stroke
				(width 0.15)
				(type solid)
			)
			(fill no)
			(layer "B.Fab")
		)
		(fp_text user "License: Apache-2.0"
			(at -1.12 -5.024 90)
			(layer "B.Fab")
			(effects
				(font
					(size 0.7 0.7)
					(thickness 0.15)
				)
				(justify left bottom mirror)
			)
		)
		(fp_text user "Author: Antmicro"
			(at -1.12 -6.224 90)
			(layer "B.Fab")
			(effects
				(font
					(size 0.7 0.7)
					(thickness 0.15)
				)
				(justify left bottom mirror)
			)
		)
		(fp_text user "${REFERENCE}"
			(at -1.12 -3.824 90)
			(layer "B.Fab")
			(effects
				(font
					(size 0.7 0.7)
					(thickness 0.15)
				)
				(justify left bottom mirror)
			)
		)
		(pad "1" smd rect
			(at -0.5 -0.65 270)
			(size 0.4 0.51)
			(layers "B.Cu" "B.Mask" "B.Paste")
			(net 1298 "Net-(Q37-G)")
			(pinfunction "G")
			(pintype "input")
		)
		(pad "2" smd rect
			(at 0.498 -0.65 270)
			(size 0.4 0.51)
			(layers "B.Cu" "B.Mask" "B.Paste")
			(net 1 "GND")
			(pinfunction "S")
			(pintype "passive")
		)
		(pad "3" smd rect
			(at 0 0.652 270)
			(size 0.4 0.51)
			(layers "B.Cu" "B.Mask" "B.Paste")
			(net 1302 "Net-(Q37-D)")
			(pinfunction "D")
			(pintype "passive")
		)
	)
	(footprint "antmicro-footprints:TP_SMD_0.75mm"
		(layer "B.Cu")
		(at 142.830532 75.81 90)
		(property "Reference" "TP34"
			(at -1.49 1.669468 0)
			(layer "B.SilkS")
			(effects
				(font
					(size 0.7 0.7)
					(thickness 0.15)
				)
				(justify left bottom mirror)
			)
		)
		(property "Value" "TP_0.75mm_SMD"
			(at 0 -1.2 90)
			(layer "B.Fab")
			(effects
				(font
					(size 0.7 0.7)
					(thickness 0.15)
				)
				(justify right top mirror)
			)
		)
		(property "Description" "SMT test point"
			(at 0 0 90)
			(layer "B.Fab")
			(hide yes)
			(effects
				(font
					(size 1.27 1.27)
					(thickness 0.15)
				)
				(justify mirror)
			)
		)
		(property "MPN" ""
			(at 0 0 270)
			(unlocked yes)
			(layer "B.Fab")
			(hide yes)
			(effects
				(font
					(size 1 1)
					(thickness 0.15)
				)
				(justify mirror)
			)
		)
		(property "Manufacturer" ""
			(at 0 0 270)
			(unlocked yes)
			(layer "B.Fab")
			(hide yes)
			(effects
				(font
					(size 1 1)
					(thickness 0.15)
				)
				(justify mirror)
			)
		)
		(property "Author" "Antmicro"
			(at 0 0 270)
			(unlocked yes)
			(layer "B.Fab")
			(hide yes)
			(effects
				(font
					(size 1 1)
					(thickness 0.15)
				)
				(justify mirror)
			)
		)
		(property "License" "Apache-2.0"
			(at 0 0 270)
			(unlocked yes)
			(layer "B.Fab")
			(hide yes)
			(effects
				(font
					(size 1 1)
					(thickness 0.15)
				)
				(justify mirror)
			)
		)
		(sheetname "/SoM_Power/")
		(sheetfile "som_power.kicad_sch")
		(attr exclude_from_pos_files exclude_from_bom)
		(fp_circle
			(center 0 0)
			(end 0.475 0)
			(stroke
				(width 0.05)
				(type default)
			)
			(fill no)
			(layer "B.CrtYd")
		)
		(fp_text user "License: Apache-2.0"
			(at -0.4 -5.101 90)
			(layer "B.Fab")
			(effects
				(font
					(size 0.7 0.7)
					(thickness 0.15)
				)
				(justify right top mirror)
			)
		)
		(fp_text user "${REFERENCE}"
			(at -0.4 -2.7 90)
			(layer "B.Fab")
			(effects
				(font
					(size 0.7 0.7)
					(thickness 0.15)
				)
				(justify right top mirror)
			)
		)
		(fp_text user "Author: Antmicro"
			(at -0.4 -3.901 90)
			(layer "B.Fab")
			(effects
				(font
					(size 0.7 0.7)
					(thickness 0.15)
				)
				(justify right top mirror)
			)
		)
		(pad "1" smd circle
			(at 0 0 90)
			(size 0.75 0.75)
			(layers "B.Cu" "B.Mask")
			(net 758 "Net-(J1A-GPIO31)")
			(pinfunction "1")
			(pintype "passive")
		)
	)
	(footprint "antmicro-footprints:C_0603_1608Metric_EIA"
		(layer "B.Cu")
		(at 200.226 145.25 90)
		(descr "Capacitor SMD 0603, IPC-7351 Density Level A")
		(tags "Capacitor 0603")
		(property "Reference" "C168"
			(at 4.15 0.5 270)
			(layer "B.SilkS")
			(effects
				(font
					(size 0.7 0.7)
					(thickness 0.15)
				)
				(justify left bottom mirror)
			)
		)
		(property "Value" "C_22u_16V_0603"
			(at -1.42757 -1.770288 270)
			(layer "B.Fab")
			(effects
				(font
					(size 0.7 0.7)
					(thickness 0.15)
				)
				(justify left bottom mirror)
			)
		)
		(property "Datasheet" "https://product.samsungsem.com/mlcc/CL10A226MO7JZN.do"
			(at 0 0 270)
			(layer "B.Fab")
			(hide yes)
			(effects
				(font
					(size 1.27 1.27)
					(thickness 0.15)
				)
				(justify mirror)
			)
		)
		(property "Description" "SMD Multilayer Ceramic Capacitor"
			(at 0 0 270)
			(layer "B.Fab")
			(hide yes)
			(effects
				(font
					(size 1.27 1.27)
					(thickness 0.15)
				)
				(justify mirror)
			)
		)
		(property "MPN" "CL10A226MO7JZNC"
			(at 0 0 90)
			(unlocked yes)
			(layer "B.Fab")
			(hide yes)
			(effects
				(font
					(size 1 1)
					(thickness 0.15)
				)
				(justify mirror)
			)
		)
		(property "Manufacturer" "Samsung Electro-Mechanics"
			(at 0 0 90)
			(unlocked yes)
			(layer "B.Fab")
			(hide yes)
			(effects
				(font
					(size 1 1)
					(thickness 0.15)
				)
				(justify mirror)
			)
		)
		(property "License" "Apache-2.0"
			(at 0 0 90)
			(unlocked yes)
			(layer "B.Fab")
			(hide yes)
			(effects
				(font
					(size 1 1)
					(thickness 0.15)
				)
				(justify mirror)
			)
		)
		(property "Author" "Antmicro"
			(at 0 0 90)
			(unlocked yes)
			(layer "B.Fab")
			(hide yes)
			(effects
				(font
					(size 1 1)
					(thickness 0.15)
				)
				(justify mirror)
			)
		)
		(property "Val" "22u"
			(at 0 0 90)
			(unlocked yes)
			(layer "B.Fab")
			(hide yes)
			(effects
				(font
					(size 1 1)
					(thickness 0.15)
				)
				(justify mirror)
			)
		)
		(property "Voltage" "16V"
			(at 0 0 90)
			(unlocked yes)
			(layer "B.Fab")
			(hide yes)
			(effects
				(font
					(size 1 1)
					(thickness 0.15)
				)
				(justify mirror)
			)
		)
		(property "Dielectric" ""
			(at 0 0 90)
			(unlocked yes)
			(layer "B.Fab")
			(hide yes)
			(effects
				(font
					(size 1 1)
					(thickness 0.15)
				)
				(justify mirror)
			)
		)
		(sheetname "/SFP/")
		(sheetfile "sfp.kicad_sch")
		(attr smd)
		(fp_line
			(start -0.15 -0.55)
			(end 0.15 -0.55)
			(stroke
				(width 0.15)
				(type solid)
			)
			(layer "B.SilkS")
		)
		(fp_line
			(start -0.15 0.55)
			(end 0.15 0.55)
			(stroke
				(width 0.15)
				(type solid)
			)
			(layer "B.SilkS")
		)
		(fp_rect
			(start -1.25 0.65)
			(end 1.25 -0.65)
			(stroke
				(width 0.05)
				(type solid)
			)
			(fill no)
			(layer "B.CrtYd")
		)
		(fp_rect
			(start -0.8 0.45)
			(end 0.8 -0.45)
			(stroke
				(width 0.15)
				(type solid)
			)
			(fill no)
			(layer "B.Fab")
		)
		(fp_text user "License: Apache-2.0"
			(at -1.682 -5.895 270)
			(layer "B.Fab")
			(effects
				(font
					(size 0.7 0.7)
					(thickness 0.15)
				)
				(justify left bottom mirror)
			)
		)
		(fp_text user "Author: Antmicro"
			(at -1.682 -4.894 270)
			(layer "B.Fab")
			(effects
				(font
					(size 0.7 0.7)
					(thickness 0.15)
				)
				(justify left bottom mirror)
			)
		)
		(fp_text user "${REFERENCE}"
			(at -1.682 -3.895 270)
			(layer "B.Fab")
			(effects
				(font
					(size 0.7 0.7)
					(thickness 0.15)
				)
				(justify left bottom mirror)
			)
		)
		(pad "1" smd roundrect
			(at -0.7 0 90)
			(size 0.8 1.1)
			(layers "B.Cu" "B.Mask" "B.Paste")
			(roundrect_rratio 0.2)
			(net 1 "GND")
			(pintype "passive")
		)
		(pad "2" smd roundrect
			(at 0.7 0 90)
			(size 0.8 1.1)
			(layers "B.Cu" "B.Mask" "B.Paste")
			(roundrect_rratio 0.2)
			(net 2 "+3V3")
			(pintype "passive")
		)
	)
	(footprint "antmicro-footprints:TSOT23-6"
		(layer "B.Cu")
		(at 232.4 108.654)
		(property "Reference" "U23"
			(at -0.9 -2.654 0)
			(layer "B.SilkS")
			(effects
				(font
					(size 0.7 0.7)
					(thickness 0.15)
				)
				(justify right top mirror)
			)
		)
		(property "Value" "AP22615A_TSOT26"
			(at 0 -2.600001 0)
			(layer "B.Fab")
			(effects
				(font
					(size 0.7 0.7)
					(thickness 0.15)
				)
				(justify right top mirror)
			)
		)
		(property "Datasheet" "https://www.mouser.com/datasheet/2/115/DIOD_S_A0008958405_1-2543193.pdf"
			(at 0 0 0)
			(layer "B.Fab")
			(hide yes)
			(effects
				(font
					(size 1.27 1.27)
					(thickness 0.15)
				)
				(justify mirror)
			)
		)
		(property "Description" "Power Load Distribution Switch, High Side, Active High, 1 Output, 5.5 V, 3.6 A, 0.04 ohm, TSOT-26-6"
			(at 0 0 0)
			(layer "B.Fab")
			(hide yes)
			(effects
				(font
					(size 1.27 1.27)
					(thickness 0.15)
				)
				(justify mirror)
			)
		)
		(property "MPN" "AP22615AWU-7"
			(at 0 0 180)
			(unlocked yes)
			(layer "B.Fab")
			(hide yes)
			(effects
				(font
					(size 1 1)
					(thickness 0.15)
				)
				(justify mirror)
			)
		)
		(property "Manufacturer" "Diodes Incorporated"
			(at 0 0 180)
			(unlocked yes)
			(layer "B.Fab")
			(hide yes)
			(effects
				(font
					(size 1 1)
					(thickness 0.15)
				)
				(justify mirror)
			)
		)
		(property "Author" "Antmicro"
			(at 0 0 180)
			(unlocked yes)
			(layer "B.Fab")
			(hide yes)
			(effects
				(font
					(size 1 1)
					(thickness 0.15)
				)
				(justify mirror)
			)
		)
		(property "License" "Apache-2.0"
			(at 0 0 180)
			(unlocked yes)
			(layer "B.Fab")
			(hide yes)
			(effects
				(font
					(size 1 1)
					(thickness 0.15)
				)
				(justify mirror)
			)
		)
		(sheetname "/Recovery USB/")
		(sheetfile "recovery_usb.kicad_sch")
		(attr smd)
		(fp_line
			(start -1 -1.55)
			(end -1 -1.4)
			(stroke
				(width 0.15)
				(type solid)
			)
			(layer "B.SilkS")
		)
		(fp_line
			(start -1 1.5)
			(end -1 1.375)
			(stroke
				(width 0.15)
				(type solid)
			)
			(layer "B.SilkS")
		)
		(fp_line
			(start 1 -1.55)
			(end -1 -1.55)
			(stroke
				(width 0.15)
				(type solid)
			)
			(layer "B.SilkS")
		)
		(fp_line
			(start 1 -1.55)
			(end 1 -1.4)
			(stroke
				(width 0.15)
				(type solid)
			)
			(layer "B.SilkS")
		)
		(fp_line
			(start 1 1.497)
			(end -1 1.5)
			(stroke
				(width 0.15)
				(type solid)
			)
			(layer "B.SilkS")
		)
		(fp_line
			(start 1 1.497)
			(end 1 1.375)
			(stroke
				(width 0.15)
				(type solid)
			)
			(layer "B.SilkS")
		)
		(fp_circle
			(center -1.44 1.5)
			(end -1.39 1.5)
			(stroke
				(width 0.15)
				(type solid)
			)
			(fill yes)
			(layer "B.SilkS")
		)
		(fp_poly
			(pts
				(xy 1.930001 1.7) (xy 1.930001 -1.7) (xy -1.930001 -1.7) (xy -1.930001 1.7)
			)
			(stroke
				(width 0.05)
				(type solid)
			)
			(fill no)
			(layer "B.CrtYd")
		)
		(fp_line
			(start -0.45 1.520999)
			(end -0.876001 1.096)
			(stroke
				(width 0.15)
				(type solid)
			)
			(layer "B.Fab")
		)
		(fp_poly
			(pts
				(xy 0.875 -1.528) (xy 0.875 1.525) (xy -0.875 1.525) (xy -0.875 -1.528)
			)
			(stroke
				(width 0.15)
				(type solid)
			)
			(fill no)
			(layer "B.Fab")
		)
		(fp_text user "${REFERENCE}"
			(at -1.93 -3.8 0)
			(layer "B.Fab")
			(effects
				(font
					(size 0.7 0.7)
					(thickness 0.15)
				)
				(justify right top mirror)
			)
		)
		(fp_text user "Author: Antmicro"
			(at -1.93 -5 0)
			(layer "B.Fab")
			(effects
				(font
					(size 0.7 0.7)
					(thickness 0.15)
				)
				(justify right top mirror)
			)
		)
		(fp_text user "License: Apache-2.0"
			(at -1.93 -6.199 0)
			(layer "B.Fab")
			(effects
				(font
					(size 0.7 0.7)
					(thickness 0.15)
				)
				(justify right top mirror)
			)
		)
		(pad "1" smd rect
			(at -1.301 0.947 90)
			(size 0.7 1.2)
			(layers "B.Cu" "B.Mask" "B.Paste")
			(net 287 "/Recovery USB/USBC2_VBUS")
			(pinfunction "OUT")
			(pintype "power_out")
		)
		(pad "2" smd rect
			(at -1.300999 -0.004 90)
			(size 0.7 1.2)
			(layers "B.Cu" "B.Mask" "B.Paste")
			(net 1 "GND")
			(pinfunction "GND")
			(pintype "power_in")
		)
		(pad "3" smd rect
			(at -1.301 -0.954 90)
			(size 0.7 1.2)
			(layers "B.Cu" "B.Mask" "B.Paste")
			(net 1243 "Net-(U23-FLG)")
			(pinfunction "FLG")
			(pintype "output")
		)
		(pad "4" smd rect
			(at 1.299 -0.954 90)
			(size 0.7 1.2)
			(layers "B.Cu" "B.Mask" "B.Paste")
			(net 890 "Net-(Q19-D)")
			(pinfunction "EN")
			(pintype "input")
		)
		(pad "5" smd rect
			(at 1.299 -0.004 90)
			(size 0.7 1.2)
			(layers "B.Cu" "B.Mask" "B.Paste")
			(net 1020 "/Recovery USB/USBC2_ISET")
			(pinfunction "ISET")
			(pintype "passive")
		)
		(pad "6" smd rect
			(at 1.299 0.947 90)
			(size 0.7 1.2)
			(layers "B.Cu" "B.Mask" "B.Paste")
			(net 5 "+5V")
			(pinfunction "IN")
			(pintype "power_in")
		)
	)
	(footprint "antmicro-footprints:TP_SMD_0.75mm"
		(layer "B.Cu")
		(at 94.9 84.6 90)
		(property "Reference" "TP35"
			(at -3.2 -0.3 90)
			(layer "B.SilkS")
			(effects
				(font
					(size 0.7 0.7)
					(thickness 0.15)
				)
				(justify right top mirror)
			)
		)
		(property "Value" "TP_0.75mm_SMD"
			(at 0 -1.2 90)
			(layer "B.Fab")
			(effects
				(font
					(size 0.7 0.7)
					(thickness 0.15)
				)
				(justify right top mirror)
			)
		)
		(property "Description" "SMT test point"
			(at 0 0 90)
			(layer "B.Fab")
			(hide yes)
			(effects
				(font
					(size 1.27 1.27)
					(thickness 0.15)
				)
				(justify mirror)
			)
		)
		(property "MPN" ""
			(at 0 0 270)
			(unlocked yes)
			(layer "B.Fab")
			(hide yes)
			(effects
				(font
					(size 1 1)
					(thickness 0.15)
				)
				(justify mirror)
			)
		)
		(property "Manufacturer" ""
			(at 0 0 270)
			(unlocked yes)
			(layer "B.Fab")
			(hide yes)
			(effects
				(font
					(size 1 1)
					(thickness 0.15)
				)
				(justify mirror)
			)
		)
		(property "Author" "Antmicro"
			(at 0 0 270)
			(unlocked yes)
			(layer "B.Fab")
			(hide yes)
			(effects
				(font
					(size 1 1)
					(thickness 0.15)
				)
				(justify mirror)
			)
		)
		(property "License" "Apache-2.0"
			(at 0 0 270)
			(unlocked yes)
			(layer "B.Fab")
			(hide yes)
			(effects
				(font
					(size 1 1)
					(thickness 0.15)
				)
				(justify mirror)
			)
		)
		(sheetname "/SoM_Power/")
		(sheetfile "som_power.kicad_sch")
		(attr exclude_from_pos_files exclude_from_bom)
		(fp_circle
			(center 0 0)
			(end 0.475 0)
			(stroke
				(width 0.05)
				(type default)
			)
			(fill no)
			(layer "B.CrtYd")
		)
		(fp_text user "Author: Antmicro"
			(at -0.4 -3.901 90)
			(layer "B.Fab")
			(effects
				(font
					(size 0.7 0.7)
					(thickness 0.15)
				)
				(justify right top mirror)
			)
		)
		(fp_text user "${REFERENCE}"
			(at -0.4 -2.7 90)
			(layer "B.Fab")
			(effects
				(font
					(size 0.7 0.7)
					(thickness 0.15)
				)
				(justify right top mirror)
			)
		)
		(fp_text user "License: Apache-2.0"
			(at -0.4 -5.101 90)
			(layer "B.Fab")
			(effects
				(font
					(size 0.7 0.7)
					(thickness 0.15)
				)
				(justify right top mirror)
			)
		)
		(pad "1" smd circle
			(at 0 0 90)
			(size 0.75 0.75)
			(layers "B.Cu" "B.Mask")
			(net 795 "Net-(J1A-POWER_INT_N)")
			(pinfunction "1")
			(pintype "passive")
		)
	)
)
